# T6G (Grand Teton) — schematic netlist excerpt (pin names and nets, part order shuffled) for the footprints in the layout excerpt that follows; sources: Cadence DE-HDL packaged netlist, KiCad conversion of 04192023_DAF0TMB3IC0_F0TG_MB_C_brd_V02_OCP.brd

R6725  Q_RES  4.7K 5% EMPTY  pkg 0201LF  page 320 : A = P1V8_CPU1_RT_1D ; B = JTAG_TEST_MODE_RT_CPU1_P0

PL28  Q_INDUCTOR4P_14  150NH IND  pkg L_TLM117513Q-151QL_11X7-5XA  page 211
  \1\  = SW_PVDDCR_CPU0_P1_SW1
  \2\  = IND_CPU0_P1_CPL5
  \3\  = IND_CPU0_P1_CPL1
  \4\  = PVDDCR_CPU0_P1

R6730  Q_RES  1K 1% EMPTY  pkg 0201LF  page 332 : A = P1V8_CPU1_RT_1D ; B = RT_CPU1_P1_VQPS
C6633  Q_CAP_DIFFBUS  DIFF BUS_0.22UF 6.3V 20% X6S  pkg C0201  page 319 : \1\ = P5E_CPU1_P0_TX_BUF_C_DP<2> ; \2\ = P5E_CPU1_P0_TX_BUF_DP<2>

(kicad_pcb
	(version 20260206)
	(generator "pcbnew")
	(generator_version "10.0")
	(general
		(thickness 1.6)
		(legacy_teardrops no)
	)
	(paper "A4")
	(title_block
		(title "04192023_DAF0TMB3IC0_F0TG_MB_C_brd_V02_OCP.brd")
		(comment 1 "Grand Teton / footprints 2411-2414 of 8354")
	)
	(layers
		(0 "F.Cu" signal "TOP")
		(4 "In1.Cu" signal "GND")
		(6 "In2.Cu" signal "IN1")
		(8 "In3.Cu" signal "GND1")
		(10 "In4.Cu" signal "IN2")
		(12 "In5.Cu" signal "GND2")
		(14 "In6.Cu" signal "IN3")
		(16 "In7.Cu" signal "GND3")
		(18 "In8.Cu" signal "VCC")
		(20 "In9.Cu" signal "VCC1")
		(22 "In10.Cu" signal "GND4")
		(24 "In11.Cu" signal "IN4")
		(26 "In12.Cu" signal "GND5")
		(28 "In13.Cu" signal "IN5")
		(30 "In14.Cu" signal "GND6")
		(32 "In15.Cu" signal "IN6")
		(34 "In16.Cu" signal "GND7")
		(2 "B.Cu" signal "BOTTOM")
		(9 "F.Adhes" user "F.Adhesive")
		(11 "B.Adhes" user "B.Adhesive")
		(13 "F.Paste" user "Package Geometry/Pastemask Top")
		(15 "B.Paste" user "Package Geometry/Pastemask Bottom")
		(5 "F.SilkS" user "Ref Des/Silkscreen Top")
		(7 "B.SilkS" user "Ref Des/Silkscreen Bottom")
		(1 "F.Mask" user "Board Geometry/Soldermask Top")
		(3 "B.Mask" user "Board Geometry/Soldermask Bottom")
		(17 "Dwgs.User" user "User.Drawings")
		(19 "Cmts.User" user "User.Comments")
		(21 "Eco1.User" user "User.Eco1")
		(23 "Eco2.User" user "User.Eco2")
		(25 "Edge.Cuts" user "Board Geometry/Outline")
		(27 "Margin" user)
		(31 "F.CrtYd" user "Package Geometry/Place Bound Top")
		(29 "B.CrtYd" user "Package Geometry/Place Bound Bottom")
		(35 "F.Fab" user "Ref Des/Assembly Top")
		(33 "B.Fab" user "Ref Des/Assembly Bottom")
	)
	(footprint ""
		(layer "F.Cu")
		(at 82.166714 -192.061084 180)
		(property "Reference" "PL28"
			(at -21.355304 3.337306 90)
			(unlocked yes)
			(layer "F.SilkS")
			(effects
				(font
					(size 0.7874 0.5842)
					(thickness 0.1524)
				)
				(justify left)
			)
		)
		(property "Value" ""
			(at 0 0 180)
			(layer "F.Fab")
			(effects
				(font
					(size 1.27 1.27)
				)
			)
		)
		(duplicate_pad_numbers_are_jumpers no)
		(fp_line
			(start 3.750056 5.500116)
			(end 3.750056 -5.500116)
			(stroke
				(width 0.1524)
				(type default)
			)
			(layer "F.SilkS")
		)
		(fp_line
			(start 3.750056 -5.500116)
			(end 2.393442 -5.500116)
			(stroke
				(width 0.1524)
				(type default)
			)
			(layer "F.SilkS")
		)
		(fp_line
			(start 2.393442 5.500116)
			(end 3.750056 5.500116)
			(stroke
				(width 0.1524)
				(type default)
			)
			(layer "F.SilkS")
		)
		(fp_line
			(start -2.393442 5.500116)
			(end -3.750056 5.500116)
			(stroke
				(width 0.1524)
				(type default)
			)
			(layer "F.SilkS")
		)
		(fp_line
			(start -3.750056 5.500116)
			(end -3.750056 -5.500116)
			(stroke
				(width 0.1524)
				(type default)
			)
			(layer "F.SilkS")
		)
		(fp_line
			(start -3.750056 -5.500116)
			(end -2.393442 -5.500116)
			(stroke
				(width 0.1524)
				(type default)
			)
			(layer "F.SilkS")
		)
		(fp_poly
			(pts
				(xy -3.9116 -4.249928) (xy -4.445 -3.983228) (xy -4.445 -4.516628)
			)
			(stroke
				(width 0)
				(type default)
			)
			(fill yes)
			(layer "F.SilkS")
		)
		(fp_line
			(start 3.750056 5.500116)
			(end 3.750056 -5.500116)
			(stroke
				(width 0.1)
				(type default)
			)
			(layer "F.Fab")
		)
		(fp_line
			(start 3.750056 -5.500116)
			(end -3.750056 -5.500116)
			(stroke
				(width 0.1)
				(type default)
			)
			(layer "F.Fab")
		)
		(fp_line
			(start -3.750056 5.500116)
			(end 3.750056 5.500116)
			(stroke
				(width 0.1)
				(type default)
			)
			(layer "F.Fab")
		)
		(fp_line
			(start -3.750056 -5.500116)
			(end -3.750056 5.500116)
			(stroke
				(width 0.1)
				(type default)
			)
			(layer "F.Fab")
		)
		(fp_poly
			(pts
				(xy -4.9276 -4.757928) (xy -4.9276 -3.741928) (xy -3.9116 -4.249928)
			)
			(stroke
				(width 0)
				(type default)
			)
			(fill yes)
			(layer "F.Fab")
		)
		(pad "1" smd rect
			(at 0 -4.249928 90)
			(size 2.413 4.5212)
			(layers "F.Cu" "F.Mask" "F.Paste")
			(net "SW_PVDDCR_CPU0_P1_SW1")
		)
		(pad "2" smd rect
			(at 0 -1.175004 90)
			(size 1.3716 4.5212)
			(layers "F.Cu" "F.Mask" "F.Paste")
			(net "IND_CPU0_P1_CPL5")
		)
		(pad "3" smd rect
			(at 0 1.175004 90)
			(size 1.3716 4.5212)
			(layers "F.Cu" "F.Mask" "F.Paste")
			(net "IND_CPU0_P1_CPL1")
		)
		(pad "4" smd rect
			(at 0 4.249928 90)
			(size 2.413 4.5212)
			(layers "F.Cu" "F.Mask" "F.Paste")
			(net "PVDDCR_CPU0_P1")
		)
	)
	(footprint ""
		(layer "F.Cu")
		(at 40.386 -391.7696 -90)
		(property "Reference" "R6725"
			(at 0 0 270)
			(layer "F.SilkS")
			(hide yes)
			(effects
				(font
					(size 1.27 1.27)
				)
			)
		)
		(property "Value" ""
			(at 0 0 270)
			(layer "F.Fab")
			(effects
				(font
					(size 1.27 1.27)
				)
			)
		)
		(duplicate_pad_numbers_are_jumpers no)
		(fp_line
			(start -0.32512 0.175006)
			(end -0.32512 -0.175006)
			(stroke
				(width 0.1)
				(type default)
			)
			(layer "F.Fab")
		)
		(fp_line
			(start 0.32512 0.175006)
			(end -0.32512 0.175006)
			(stroke
				(width 0.1)
				(type default)
			)
			(layer "F.Fab")
		)
		(fp_line
			(start -0.32512 -0.175006)
			(end 0.32512 -0.175006)
			(stroke
				(width 0.1)
				(type default)
			)
			(layer "F.Fab")
		)
		(fp_line
			(start 0.32512 -0.175006)
			(end 0.32512 0.175006)
			(stroke
				(width 0.1)
				(type default)
			)
			(layer "F.Fab")
		)
		(pad "1" smd rect
			(at -0.2667 0 270)
			(size 0.3048 0.381)
			(layers "F.Cu" "F.Mask" "F.Paste")
			(net "P1V8_CPU1_RT_1D")
		)
		(pad "2" smd rect
			(at 0.2667 0 90)
			(size 0.3048 0.381)
			(layers "F.Cu" "F.Mask" "F.Paste")
			(net "JTAG_TEST_MODE_RT_CPU1_P0")
		)
	)
	(footprint ""
		(layer "F.Cu")
		(at 54.809644 -408.517344 -90)
		(property "Reference" "C6633"
			(at 0 0 270)
			(layer "F.SilkS")
			(hide yes)
			(effects
				(font
					(size 1.27 1.27)
				)
			)
		)
		(property "Value" ""
			(at 0 0 270)
			(layer "F.Fab")
			(effects
				(font
					(size 1.27 1.27)
				)
			)
		)
		(duplicate_pad_numbers_are_jumpers no)
		(fp_line
			(start -0.299974 0.150114)
			(end -0.299974 -0.150114)
			(stroke
				(width 0.1)
				(type default)
			)
			(layer "F.Fab")
		)
		(fp_line
			(start 0.299974 0.150114)
			(end -0.299974 0.150114)
			(stroke
				(width 0.1)
				(type default)
			)
			(layer "F.Fab")
		)
		(fp_line
			(start -0.299974 -0.150114)
			(end 0.299974 -0.150114)
			(stroke
				(width 0.1)
				(type default)
			)
			(layer "F.Fab")
		)
		(fp_line
			(start 0.299974 -0.150114)
			(end 0.299974 0.150114)
			(stroke
				(width 0.1)
				(type default)
			)
			(layer "F.Fab")
		)
		(pad "1" smd rect
			(at -0.2667 0 270)
			(size 0.3048 0.381)
			(layers "F.Cu" "F.Mask" "F.Paste")
			(net "P5E_CPU1_P0_TX_BUF_C_DP<2>")
		)
		(pad "2" smd rect
			(at 0.2667 0 270)
			(size 0.3048 0.381)
			(layers "F.Cu" "F.Mask" "F.Paste")
			(net "P5E_CPU1_P0_TX_BUF_DP<2>")
		)
	)
	(footprint ""
		(layer "F.Cu")
		(at 99.080828 -395.6304 -90)
		(property "Reference" "R6730"
			(at 0 0 270)
			(layer "F.SilkS")
			(hide yes)
			(effects
				(font
					(size 1.27 1.27)
				)
			)
		)
		(property "Value" ""
			(at 0 0 270)
			(layer "F.Fab")
			(effects
				(font
					(size 1.27 1.27)
				)
			)
		)
		(duplicate_pad_numbers_are_jumpers no)
		(fp_line
			(start -0.32512 0.175006)
			(end -0.32512 -0.175006)
			(stroke
				(width 0.1)
				(type default)
			)
			(layer "F.Fab")
		)
		(fp_line
			(start 0.32512 0.175006)
			(end -0.32512 0.175006)
			(stroke
				(width 0.1)
				(type default)
			)
			(layer "F.Fab")
		)
		(fp_line
			(start -0.32512 -0.175006)
			(end 0.32512 -0.175006)
			(stroke
				(width 0.1)
				(type default)
			)
			(layer "F.Fab")
		)
		(fp_line
			(start 0.32512 -0.175006)
			(end 0.32512 0.175006)
			(stroke
				(width 0.1)
				(type default)
			)
			(layer "F.Fab")
		)
		(pad "1" smd rect
			(at -0.2667 0 270)
			(size 0.3048 0.381)
			(layers "F.Cu" "F.Mask" "F.Paste")
			(net "P1V8_CPU1_RT_1D")
		)
		(pad "2" smd rect
			(at 0.2667 0 90)
			(size 0.3048 0.381)
			(layers "F.Cu" "F.Mask" "F.Paste")
			(net "RT_CPU1_P1_VQPS")
		)
	)
)
